# S9S_MB_2U (Grand Teton) — schematic netlist excerpt (pin names and nets, part order shuffled) for the footprints in the layout excerpt that follows; sources: Cadence DE-HDL packaged netlist, KiCad conversion of 03242023_DA0F0TMBIJ0_F0T_Motherboard_J_brd_V01_OCP.brd

PR2149  Q_RES  0 5% CHIP  pkg 0402LF  page 301 : A = HSC_VDD_R ; B = HSC_VDD
ME11  ME_DUMMY_SYMBOL  PICKUP_SMDC20 EMPTY  pkg PICKUP_SMDC20  page 312
R1410  Q_RES  2K 1% CHIP  pkg 0402LF  page 219 : A = FM_PVCCFA_EHV_CPU1_R_EN ; B = GND

(kicad_pcb
	(version 20260206)
	(generator "pcbnew")
	(generator_version "10.0")
	(general
		(thickness 1.6)
		(legacy_teardrops no)
	)
	(paper "A4")
	(title_block
		(title "03242023_DA0F0TMBIJ0_F0T_Motherboard_J_brd_V01_OCP.brd")
		(comment 1 "Grand Teton / footprints 4542-4544 of 6105")
	)
	(layers
		(0 "F.Cu" signal "TOP")
		(4 "In1.Cu" signal "GND")
		(6 "In2.Cu" signal "IN1")
		(8 "In3.Cu" signal "GND1")
		(10 "In4.Cu" signal "IN2")
		(12 "In5.Cu" signal "GND2")
		(14 "In6.Cu" signal "IN3")
		(16 "In7.Cu" signal "GND3")
		(18 "In8.Cu" signal "VCC")
		(20 "In9.Cu" signal "VCC1")
		(22 "In10.Cu" signal "GND4")
		(24 "In11.Cu" signal "IN4")
		(26 "In12.Cu" signal "GND5")
		(28 "In13.Cu" signal "IN5")
		(30 "In14.Cu" signal "GND6")
		(32 "In15.Cu" signal "IN6")
		(34 "In16.Cu" signal "GND7")
		(2 "B.Cu" signal "BOTTOM")
		(9 "F.Adhes" user "F.Adhesive")
		(11 "B.Adhes" user "B.Adhesive")
		(13 "F.Paste" user "Package Geometry/Pastemask Top")
		(15 "B.Paste" user "Package Geometry/Pastemask Bottom")
		(5 "F.SilkS" user "Ref Des/Silkscreen Top")
		(7 "B.SilkS" user "Ref Des/Silkscreen Bottom")
		(1 "F.Mask" user "Board Geometry/Soldermask Top")
		(3 "B.Mask" user "Board Geometry/Soldermask Bottom")
		(17 "Dwgs.User" user "User.Drawings")
		(19 "Cmts.User" user "User.Comments")
		(21 "Eco1.User" user "User.Eco1")
		(23 "Eco2.User" user "User.Eco2")
		(25 "Edge.Cuts" user "Board Geometry/Outline")
		(27 "Margin" user)
		(31 "F.CrtYd" user "Package Geometry/Place Bound Top")
		(29 "B.CrtYd" user "Package Geometry/Place Bound Bottom")
		(35 "F.Fab" user "Ref Des/Assembly Top")
		(33 "B.Fab" user "Ref Des/Assembly Bottom")
	)
	(footprint ""
		(layer "B.Cu")
		(at 164.64788 -118.836948)
		(property "Reference" "R1410"
			(at 0 0 0)
			(layer "B.SilkS")
			(hide yes)
			(effects
				(font
					(size 1.27 1.27)
				)
				(justify mirror)
			)
		)
		(property "Value" ""
			(at 0 0 0)
			(layer "B.Fab")
			(effects
				(font
					(size 1.27 1.27)
				)
				(justify mirror)
			)
		)
		(duplicate_pad_numbers_are_jumpers no)
		(fp_line
			(start -0.7874 -0.4064)
			(end -0.7874 0.4064)
			(stroke
				(width 0.1524)
				(type default)
			)
			(layer "B.SilkS")
		)
		(fp_line
			(start -0.7874 0.4064)
			(end 0.7874 0.4064)
			(stroke
				(width 0.1524)
				(type default)
			)
			(layer "B.SilkS")
		)
		(fp_line
			(start 0.7874 -0.4064)
			(end -0.7874 -0.4064)
			(stroke
				(width 0.1524)
				(type default)
			)
			(layer "B.SilkS")
		)
		(fp_line
			(start 0.7874 0.4064)
			(end 0.7874 -0.4064)
			(stroke
				(width 0.1524)
				(type default)
			)
			(layer "B.SilkS")
		)
		(fp_line
			(start -0.67945 -0.3048)
			(end -0.67945 0.3048)
			(stroke
				(width 0.1)
				(type default)
			)
			(layer "B.Fab")
		)
		(fp_line
			(start -0.67945 0.3048)
			(end -0.120396 0.3048)
			(stroke
				(width 0.1)
				(type default)
			)
			(layer "B.Fab")
		)
		(fp_line
			(start -0.12065 -0.3048)
			(end -0.67945 -0.3048)
			(stroke
				(width 0.1)
				(type default)
			)
			(layer "B.Fab")
		)
		(fp_line
			(start -0.12065 -0.2794)
			(end -0.12065 -0.3048)
			(stroke
				(width 0.1)
				(type default)
			)
			(layer "B.Fab")
		)
		(fp_line
			(start -0.120396 0.2794)
			(end 0.12065 0.2794)
			(stroke
				(width 0.1)
				(type default)
			)
			(layer "B.Fab")
		)
		(fp_line
			(start -0.120396 0.3048)
			(end -0.120396 0.2794)
			(stroke
				(width 0.1)
				(type default)
			)
			(layer "B.Fab")
		)
		(fp_line
			(start 0.12065 -0.305054)
			(end 0.12065 -0.2794)
			(stroke
				(width 0.1)
				(type default)
			)
			(layer "B.Fab")
		)
		(fp_line
			(start 0.12065 -0.2794)
			(end -0.12065 -0.2794)
			(stroke
				(width 0.1)
				(type default)
			)
			(layer "B.Fab")
		)
		(fp_line
			(start 0.12065 0.2794)
			(end 0.12065 0.3048)
			(stroke
				(width 0.1)
				(type default)
			)
			(layer "B.Fab")
		)
		(fp_line
			(start 0.12065 0.3048)
			(end 0.67945 0.3048)
			(stroke
				(width 0.1)
				(type default)
			)
			(layer "B.Fab")
		)
		(fp_line
			(start 0.67945 -0.305054)
			(end 0.12065 -0.305054)
			(stroke
				(width 0.1)
				(type default)
			)
			(layer "B.Fab")
		)
		(fp_line
			(start 0.67945 0.3048)
			(end 0.67945 -0.305054)
			(stroke
				(width 0.1)
				(type default)
			)
			(layer "B.Fab")
		)
		(pad "1" smd circle
			(at 0.40005 0 180)
			(size 0 0)
			(layers "B.Cu" "B.Mask" "B.Paste")
			(net "FM_PVCCFA_EHV_CPU1_R_EN")
		)
		(pad "2" smd circle
			(at -0.40005 0 180)
			(size 0 0)
			(layers "B.Cu" "B.Mask" "B.Paste")
			(net "GND")
		)
	)
	(footprint ""
		(layer "B.Cu")
		(at 334.02016 -386.8928)
		(property "Reference" "ME11"
			(at 9.652 -9.540748 0)
			(unlocked yes)
			(layer "B.SilkS")
			(effects
				(font
					(size 0.7874 0.5842)
					(thickness 0.1524)
				)
				(justify left mirror)
			)
		)
		(property "Value" ""
			(at 0 0 0)
			(layer "B.Fab")
			(effects
				(font
					(size 1.27 1.27)
				)
				(justify mirror)
			)
		)
		(duplicate_pad_numbers_are_jumpers no)
		(zone
			(layer "B.Cu")
			(hatch none 0.5)
			(connect_pads
				(clearance 0)
			)
			(min_thickness 0.25)
			(keepout
				(tracks allowed)
				(vias allowed)
				(pads allowed)
				(copperpour allowed)
				(footprints not_allowed)
			)
			(placement
				(enabled no)
				(sheetname "")
			)
			(fill
				(thermal_gap 0.5)
				(thermal_bridge_width 0.5)
				(island_removal_mode 0)
			)
			(polygon
				(pts
					(arc
						(start 344.02014 -386.8928)
						(mid 324.02018 -386.8928)
						(end 344.02014 -386.8928)
					)
				)
			)
		)
	)
	(footprint ""
		(layer "B.Cu")
		(at 179.352448 -404.287482)
		(property "Reference" "PR2149"
			(at 0 0 0)
			(layer "B.SilkS")
			(hide yes)
			(effects
				(font
					(size 1.27 1.27)
				)
				(justify mirror)
			)
		)
		(property "Value" ""
			(at 0 0 0)
			(layer "B.Fab")
			(effects
				(font
					(size 1.27 1.27)
				)
				(justify mirror)
			)
		)
		(duplicate_pad_numbers_are_jumpers no)
		(fp_line
			(start -0.7874 -0.4064)
			(end -0.7874 0.4064)
			(stroke
				(width 0.1524)
				(type default)
			)
			(layer "B.SilkS")
		)
		(fp_line
			(start -0.7874 0.4064)
			(end 0.7874 0.4064)
			(stroke
				(width 0.1524)
				(type default)
			)
			(layer "B.SilkS")
		)
		(fp_line
			(start 0.7874 -0.4064)
			(end -0.7874 -0.4064)
			(stroke
				(width 0.1524)
				(type default)
			)
			(layer "B.SilkS")
		)
		(fp_line
			(start 0.7874 0.4064)
			(end 0.7874 -0.4064)
			(stroke
				(width 0.1524)
				(type default)
			)
			(layer "B.SilkS")
		)
		(fp_line
			(start -0.67945 -0.3048)
			(end -0.67945 0.3048)
			(stroke
				(width 0.1)
				(type default)
			)
			(layer "B.Fab")
		)
		(fp_line
			(start -0.67945 0.3048)
			(end -0.120396 0.3048)
			(stroke
				(width 0.1)
				(type default)
			)
			(layer "B.Fab")
		)
		(fp_line
			(start -0.12065 -0.3048)
			(end -0.67945 -0.3048)
			(stroke
				(width 0.1)
				(type default)
			)
			(layer "B.Fab")
		)
		(fp_line
			(start -0.12065 -0.2794)
			(end -0.12065 -0.3048)
			(stroke
				(width 0.1)
				(type default)
			)
			(layer "B.Fab")
		)
		(fp_line
			(start -0.120396 0.2794)
			(end 0.12065 0.2794)
			(stroke
				(width 0.1)
				(type default)
			)
			(layer "B.Fab")
		)
		(fp_line
			(start -0.120396 0.3048)
			(end -0.120396 0.2794)
			(stroke
				(width 0.1)
				(type default)
			)
			(layer "B.Fab")
		)
		(fp_line
			(start 0.12065 -0.305054)
			(end 0.12065 -0.2794)
			(stroke
				(width 0.1)
				(type default)
			)
			(layer "B.Fab")
		)
		(fp_line
			(start 0.12065 -0.2794)
			(end -0.12065 -0.2794)
			(stroke
				(width 0.1)
				(type default)
			)
			(layer "B.Fab")
		)
		(fp_line
			(start 0.12065 0.2794)
			(end 0.12065 0.3048)
			(stroke
				(width 0.1)
				(type default)
			)
			(layer "B.Fab")
		)
		(fp_line
			(start 0.12065 0.3048)
			(end 0.67945 0.3048)
			(stroke
				(width 0.1)
				(type default)
			)
			(layer "B.Fab")
		)
		(fp_line
			(start 0.67945 -0.305054)
			(end 0.12065 -0.305054)
			(stroke
				(width 0.1)
				(type default)
			)
			(layer "B.Fab")
		)
		(fp_line
			(start 0.67945 0.3048)
			(end 0.67945 -0.305054)
			(stroke
				(width 0.1)
				(type default)
			)
			(layer "B.Fab")
		)
		(pad "1" smd circle
			(at 0.40005 0 180)
			(size 0 0)
			(layers "B.Cu" "B.Mask" "B.Paste")
			(net "HSC_VDD_R")
		)
		(pad "2" smd circle
			(at -0.40005 0 180)
			(size 0 0)
			(layers "B.Cu" "B.Mask" "B.Paste")
			(net "HSC_VDD")
		)
	)
)
